(kicad_pcb
	(version 20260206)
	(generator "pcbnew")
	(generator_version "10.0")
	(general
		(thickness 1.6)
		(legacy_teardrops no)
	)
	(paper "A4")
	(title_block
		(title "timecard-production-celestica-r4006 — R4006-B0001-02_R01.brd")
		(comment 1 "Time Appliance Project (Time Card) / footprints 1006-1011 of 1113")
	)
	(layers
		(0 "F.Cu" signal "TOP")
		(4 "In1.Cu" signal "L02_GND1")
		(6 "In2.Cu" signal "L03_SIG1")
		(8 "In3.Cu" signal "L04_GND2")
		(10 "In4.Cu" signal "L05_VCC1")
		(12 "In5.Cu" signal "L06_VCC2")
		(14 "In6.Cu" signal "L07_GND3")
		(16 "In7.Cu" signal "L08_SIG2")
		(18 "In8.Cu" signal "L09_GND4")
		(2 "B.Cu" signal "BOTTOM")
		(9 "F.Adhes" user "F.Adhesive")
		(11 "B.Adhes" user "B.Adhesive")
		(13 "F.Paste" user "Package Geometry/Pastemask Top")
		(15 "B.Paste" user "Package Geometry/Pastemask Bottom")
		(5 "F.SilkS" user "Ref Des/Silkscreen Top")
		(7 "B.SilkS" user "Ref Des/Silkscreen Bottom")
		(1 "F.Mask" user "Board Geometry/Soldermask Top")
		(3 "B.Mask" user "Board Geometry/Soldermask Bottom")
		(17 "Dwgs.User" user "User.Drawings")
		(19 "Cmts.User" user "User.Comments")
		(21 "Eco1.User" user "User.Eco1")
		(23 "Eco2.User" user "User.Eco2")
		(25 "Edge.Cuts" user "Board Geometry/Outline")
		(27 "Margin" user)
		(31 "F.CrtYd" user "Package Geometry/Place Bound Top")
		(29 "B.CrtYd" user "Package Geometry/Place Bound Bottom")
		(35 "F.Fab" user "Ref Des/Assembly Top")
		(33 "B.Fab" user "Ref Des/Assembly Bottom")
	)
	(footprint ""
		(layer "B.Cu")
		(at 24.13 -91.059 -90)
		(property "Reference" "R467"
			(at -2.286 5.11937 270)
			(unlocked yes)
			(layer "B.SilkS")
			(effects
				(font
					(size 0.7874 0.5842)
					(thickness 0.1524)
				)
				(justify mirror)
			)
		)
		(property "Value" "VAL*"
			(at -0.02032 2.13233 270)
			(unlocked yes)
			(layer "B.Fab")
			(hide yes)
			(effects
				(font
					(size 0.7874 0.5842)
					(thickness 0.1524)
				)
				(justify mirror)
			)
		)
		(property "Tolerance" "TOL*"
			(at -0.044704 3.05435 270)
			(unlocked yes)
			(layer "Cmts.User")
			(hide yes)
			(effects
				(font
					(size 0.7874 0.5842)
					(thickness 0.1524)
				)
				(justify mirror)
			)
		)
		(property "User Part Number" "PARTNUM*"
			(at -0.02032 4.024884 270)
			(unlocked yes)
			(layer "Cmts.User")
			(hide yes)
			(effects
				(font
					(size 0.7874 0.5842)
					(thickness 0.1524)
				)
				(justify mirror)
			)
		)
		(property "Device Type" "RESISTOR-G155-133R0-01,33OHM,1%"
			(at -0.008382 1.210564 270)
			(unlocked yes)
			(layer "B.Fab")
			(hide yes)
			(effects
				(font
					(size 0.7874 0.5842)
					(thickness 0.1524)
				)
				(justify mirror)
			)
		)
		(duplicate_pad_numbers_are_jumpers no)
		(fp_line
			(start -1.143 0.5588)
			(end -1.143 -0.5588)
			(stroke
				(width 0.1)
				(type default)
			)
			(layer "B.SilkS")
		)
		(fp_line
			(start 1.143 0.5588)
			(end -1.143 0.5588)
			(stroke
				(width 0.1)
				(type default)
			)
			(layer "B.SilkS")
		)
		(fp_line
			(start -1.143 -0.5588)
			(end 1.143 -0.5588)
			(stroke
				(width 0.1)
				(type default)
			)
			(layer "B.SilkS")
		)
		(fp_line
			(start 1.143 -0.5588)
			(end 1.143 0.5588)
			(stroke
				(width 0.1)
				(type default)
			)
			(layer "B.SilkS")
		)
		(fp_poly
			(pts
				(xy 1.143 0.5588) (xy -1.143 0.5588) (xy -1.143 -0.5588) (xy 1.143 -0.5588)
			)
			(stroke
				(width 0)
				(type default)
			)
			(fill no)
			(layer "B.CrtYd")
		)
		(fp_line
			(start -0.508 0.3048)
			(end -0.508 -0.3048)
			(stroke
				(width 0.1)
				(type default)
			)
			(layer "B.Fab")
		)
		(fp_line
			(start 0.508 0.3048)
			(end -0.508 0.3048)
			(stroke
				(width 0.1)
				(type default)
			)
			(layer "B.Fab")
		)
		(fp_line
			(start -0.508 -0.3048)
			(end 0.508 -0.3048)
			(stroke
				(width 0.1)
				(type default)
			)
			(layer "B.Fab")
		)
		(fp_line
			(start 0.508 -0.3048)
			(end 0.508 0.3048)
			(stroke
				(width 0.1)
				(type default)
			)
			(layer "B.Fab")
		)
		(pad "1" smd rect
			(at 0.5334 0 90)
			(size 0.7112 0.6096)
			(layers "B.Cu" "B.Mask" "B.Paste")
			(net "R_FT4232_TCK")
		)
		(pad "2" smd rect
			(at -0.5334 0 90)
			(size 0.7112 0.6096)
			(layers "B.Cu" "B.Mask" "B.Paste")
			(net "FT4232_TCK_SCLK")
		)
		(zone
			(layer "B.Cu")
			(hatch none 0.5)
			(connect_pads
				(clearance 0)
			)
			(min_thickness 0.25)
			(keepout
				(tracks allowed)
				(vias not_allowed)
				(pads allowed)
				(copperpour not_allowed)
				(footprints allowed)
			)
			(placement
				(enabled no)
				(sheetname "")
			)
			(fill
				(thermal_gap 0.5)
				(thermal_bridge_width 0.5)
				(island_removal_mode 0)
			)
			(polygon
				(pts
					(xy 23.8252 -90.9828) (xy 24.4348 -90.9828) (xy 24.4348 -91.1352) (xy 23.8252 -91.1352)
				)
			)
		)
		(zone
			(layer "B.Cu")
			(hatch none 0.5)
			(connect_pads
				(clearance 0)
			)
			(min_thickness 0.25)
			(keepout
				(tracks not_allowed)
				(vias allowed)
				(pads allowed)
				(copperpour not_allowed)
				(footprints allowed)
			)
			(placement
				(enabled no)
				(sheetname "")
			)
			(fill
				(thermal_gap 0.5)
				(thermal_bridge_width 0.5)
				(island_removal_mode 0)
			)
			(polygon
				(pts
					(xy 23.8252 -90.9828) (xy 24.4348 -90.9828) (xy 24.4348 -91.1352) (xy 23.8252 -91.1352)
				)
			)
		)
	)
	(footprint ""
		(layer "B.Cu")
		(at 117.347238 -48.823118 180)
		(property "Reference" "C215"
			(at 0.634238 1.945132 0)
			(unlocked yes)
			(layer "B.SilkS")
			(effects
				(font
					(size 0.635 0.4064)
					(thickness 0.1524)
				)
				(justify mirror)
			)
		)
		(property "Value" "VAL*"
			(at 0 3.718306 180)
			(unlocked yes)
			(layer "B.Fab")
			(hide yes)
			(effects
				(font
					(size 0.7874 0.5842)
					(thickness 0.127)
				)
				(justify mirror)
			)
		)
		(property "Tolerance" "TOL*"
			(at 0 4.861306 180)
			(unlocked yes)
			(layer "Cmts.User")
			(hide yes)
			(effects
				(font
					(size 0.7874 0.5842)
					(thickness 0.127)
				)
				(justify mirror)
			)
		)
		(property "User Part Number" "PARTNUM*"
			(at 0 2.575306 180)
			(unlocked yes)
			(layer "Cmts.User")
			(hide yes)
			(effects
				(font
					(size 0.7874 0.5842)
					(thickness 0.127)
				)
				(justify mirror)
			)
		)
		(property "Device Type" "CAPACITOR-G105-0B104-CK,0.1UF,A"
			(at 0 1.432306 180)
			(unlocked yes)
			(layer "B.Fab")
			(hide yes)
			(effects
				(font
					(size 0.7874 0.5842)
					(thickness 0.127)
				)
				(justify mirror)
			)
		)
		(duplicate_pad_numbers_are_jumpers no)
		(fp_line
			(start 0.970026 0.4699)
			(end 0.970026 -0.4699)
			(stroke
				(width 0.1)
				(type default)
			)
			(layer "B.SilkS")
		)
		(fp_line
			(start 0.970026 -0.4699)
			(end -0.970026 -0.4699)
			(stroke
				(width 0.1)
				(type default)
			)
			(layer "B.SilkS")
		)
		(fp_line
			(start -0.970026 0.4699)
			(end 0.970026 0.4699)
			(stroke
				(width 0.1)
				(type default)
			)
			(layer "B.SilkS")
		)
		(fp_line
			(start -0.970026 -0.4699)
			(end -0.970026 0.4699)
			(stroke
				(width 0.1)
				(type default)
			)
			(layer "B.SilkS")
		)
		(fp_poly
			(pts
				(xy 0.970026 0.4699) (xy -0.970026 0.4699) (xy -0.970026 -0.4699) (xy 0.970026 -0.4699)
			)
			(stroke
				(width 0)
				(type default)
			)
			(fill no)
			(layer "B.CrtYd")
		)
		(fp_line
			(start 0.508 0.3048)
			(end 0.508 -0.3048)
			(stroke
				(width 0.1)
				(type default)
			)
			(layer "B.Fab")
		)
		(fp_line
			(start 0.508 -0.3048)
			(end -0.508 -0.3048)
			(stroke
				(width 0.1)
				(type default)
			)
			(layer "B.Fab")
		)
		(fp_line
			(start -0.508 0.3048)
			(end 0.508 0.3048)
			(stroke
				(width 0.1)
				(type default)
			)
			(layer "B.Fab")
		)
		(fp_line
			(start -0.508 -0.3048)
			(end -0.508 0.3048)
			(stroke
				(width 0.1)
				(type default)
			)
			(layer "B.Fab")
		)
		(pad "1" smd circle
			(at 0.500126 0)
			(size 0.635 0.635)
			(layers "B.Cu" "B.Mask" "B.Paste")
			(net "XP3R3V_FPGA")
		)
		(pad "2" smd circle
			(at -0.500126 0)
			(size 0.635 0.635)
			(layers "B.Cu" "B.Mask" "B.Paste")
			(net "SG")
		)
	)
	(footprint ""
		(layer "B.Cu")
		(at 36.9824 -100.2284)
		(property "Reference" "R48"
			(at -4.0386 0.64897 0)
			(unlocked yes)
			(layer "B.SilkS")
			(effects
				(font
					(size 0.7874 0.5842)
					(thickness 0.1524)
				)
				(justify mirror)
			)
		)
		(property "Value" "VAL*"
			(at -0.02032 2.13233 0)
			(unlocked yes)
			(layer "B.Fab")
			(hide yes)
			(effects
				(font
					(size 0.7874 0.5842)
					(thickness 0.1524)
				)
				(justify mirror)
			)
		)
		(property "Device Type" "RESISTOR-A155-05101-DL,5.1KOHMA"
			(at -0.008382 1.210564 0)
			(unlocked yes)
			(layer "B.Fab")
			(hide yes)
			(effects
				(font
					(size 0.7874 0.5842)
					(thickness 0.1524)
				)
				(justify mirror)
			)
		)
		(property "User Part Number" "PARTNUM*"
			(at -0.02032 4.024884 0)
			(unlocked yes)
			(layer "Cmts.User")
			(hide yes)
			(effects
				(font
					(size 0.7874 0.5842)
					(thickness 0.1524)
				)
				(justify mirror)
			)
		)
		(property "Tolerance" "TOL*"
			(at -0.044704 3.05435 0)
			(unlocked yes)
			(layer "Cmts.User")
			(hide yes)
			(effects
				(font
					(size 0.7874 0.5842)
					(thickness 0.1524)
				)
				(justify mirror)
			)
		)
		(duplicate_pad_numbers_are_jumpers no)
		(fp_line
			(start -1.143 -0.5588)
			(end 1.143 -0.5588)
			(stroke
				(width 0.1)
				(type default)
			)
			(layer "B.SilkS")
		)
		(fp_line
			(start -1.143 0.5588)
			(end -1.143 -0.5588)
			(stroke
				(width 0.1)
				(type default)
			)
			(layer "B.SilkS")
		)
		(fp_line
			(start 1.143 -0.5588)
			(end 1.143 0.5588)
			(stroke
				(width 0.1)
				(type default)
			)
			(layer "B.SilkS")
		)
		(fp_line
			(start 1.143 0.5588)
			(end -1.143 0.5588)
			(stroke
				(width 0.1)
				(type default)
			)
			(layer "B.SilkS")
		)
		(fp_rect
			(start 1.143 -0.5588)
			(end -1.143 0.5588)
			(stroke
				(width 0)
				(type default)
			)
			(fill no)
			(layer "B.CrtYd")
		)
		(fp_line
			(start -0.508 -0.3048)
			(end 0.508 -0.3048)
			(stroke
				(width 0.1)
				(type default)
			)
			(layer "B.Fab")
		)
		(fp_line
			(start -0.508 0.3048)
			(end -0.508 -0.3048)
			(stroke
				(width 0.1)
				(type default)
			)
			(layer "B.Fab")
		)
		(fp_line
			(start 0.508 -0.3048)
			(end 0.508 0.3048)
			(stroke
				(width 0.1)
				(type default)
			)
			(layer "B.Fab")
		)
		(fp_line
			(start 0.508 0.3048)
			(end -0.508 0.3048)
			(stroke
				(width 0.1)
				(type default)
			)
			(layer "B.Fab")
		)
		(pad "1" smd rect
			(at 0.5334 0 180)
			(size 0.7112 0.6096)
			(layers "B.Cu" "B.Mask" "B.Paste")
			(net "R_XP5R0V_EN")
		)
		(pad "2" smd rect
			(at -0.5334 0 180)
			(size 0.7112 0.6096)
			(layers "B.Cu" "B.Mask" "B.Paste")
			(net "SG")
		)
		(zone
			(layer "B.Cu")
			(hatch none 0.5)
			(connect_pads
				(clearance 0)
			)
			(min_thickness 0.25)
			(keepout
				(tracks allowed)
				(vias not_allowed)
				(pads allowed)
				(copperpour not_allowed)
				(footprints allowed)
			)
			(placement
				(enabled no)
				(sheetname "")
			)
			(fill
				(thermal_gap 0.5)
				(thermal_bridge_width 0.5)
				(island_removal_mode 0)
			)
			(polygon
				(pts
					(xy 37.0586 -100.5332) (xy 36.9062 -100.5332) (xy 36.9062 -99.9236) (xy 37.0586 -99.9236)
				)
			)
		)
	)
	(footprint ""
		(layer "B.Cu")
		(at 117.84711 -47.323248 -90)
		(property "Reference" "C202"
			(at -1.698752 -1.88214 270)
			(unlocked yes)
			(layer "B.SilkS")
			(effects
				(font
					(size 0.635 0.4064)
					(thickness 0.1524)
				)
				(justify mirror)
			)
		)
		(property "Value" "VAL*"
			(at 0 3.718306 270)
			(unlocked yes)
			(layer "B.Fab")
			(hide yes)
			(effects
				(font
					(size 0.7874 0.5842)
					(thickness 0.127)
				)
				(justify mirror)
			)
		)
		(property "Tolerance" "TOL*"
			(at 0 4.861306 270)
			(unlocked yes)
			(layer "Cmts.User")
			(hide yes)
			(effects
				(font
					(size 0.7874 0.5842)
					(thickness 0.127)
				)
				(justify mirror)
			)
		)
		(property "User Part Number" "PARTNUM*"
			(at 0 2.575306 270)
			(unlocked yes)
			(layer "Cmts.User")
			(hide yes)
			(effects
				(font
					(size 0.7874 0.5842)
					(thickness 0.127)
				)
				(justify mirror)
			)
		)
		(property "Device Type" "CAPACITOR-G105-0B104-CK,0.1UF,A"
			(at 0 1.432306 270)
			(unlocked yes)
			(layer "B.Fab")
			(hide yes)
			(effects
				(font
					(size 0.7874 0.5842)
					(thickness 0.127)
				)
				(justify mirror)
			)
		)
		(duplicate_pad_numbers_are_jumpers no)
		(fp_line
			(start -0.970026 0.4699)
			(end 0.970026 0.4699)
			(stroke
				(width 0.1)
				(type default)
			)
			(layer "B.SilkS")
		)
		(fp_line
			(start 0.970026 0.4699)
			(end 0.970026 -0.4699)
			(stroke
				(width 0.1)
				(type default)
			)
			(layer "B.SilkS")
		)
		(fp_line
			(start -0.970026 -0.4699)
			(end -0.970026 0.4699)
			(stroke
				(width 0.1)
				(type default)
			)
			(layer "B.SilkS")
		)
		(fp_line
			(start 0.970026 -0.4699)
			(end -0.970026 -0.4699)
			(stroke
				(width 0.1)
				(type default)
			)
			(layer "B.SilkS")
		)
		(fp_poly
			(pts
				(xy 0.970026 0.4699) (xy -0.970026 0.4699) (xy -0.970026 -0.4699) (xy 0.970026 -0.4699)
			)
			(stroke
				(width 0)
				(type default)
			)
			(fill no)
			(layer "B.CrtYd")
		)
		(fp_line
			(start -0.508 0.3048)
			(end 0.508 0.3048)
			(stroke
				(width 0.1)
				(type default)
			)
			(layer "B.Fab")
		)
		(fp_line
			(start 0.508 0.3048)
			(end 0.508 -0.3048)
			(stroke
				(width 0.1)
				(type default)
			)
			(layer "B.Fab")
		)
		(fp_line
			(start -0.508 -0.3048)
			(end -0.508 0.3048)
			(stroke
				(width 0.1)
				(type default)
			)
			(layer "B.Fab")
		)
		(fp_line
			(start 0.508 -0.3048)
			(end -0.508 -0.3048)
			(stroke
				(width 0.1)
				(type default)
			)
			(layer "B.Fab")
		)
		(pad "1" smd circle
			(at 0.500126 0 90)
			(size 0.635 0.635)
			(layers "B.Cu" "B.Mask" "B.Paste")
			(net "XP3R3V_FPGA")
		)
		(pad "2" smd circle
			(at -0.500126 0 90)
			(size 0.635 0.635)
			(layers "B.Cu" "B.Mask" "B.Paste")
			(net "SG")
		)
	)
	(footprint ""
		(layer "B.Cu")
		(at 21.0566 -40.4876)
		(property "Reference" "R26"
			(at -0.381 4.86537 0)
			(unlocked yes)
			(layer "B.SilkS")
			(effects
				(font
					(size 0.7874 0.5842)
					(thickness 0.1524)
				)
				(justify mirror)
			)
		)
		(property "Value" "VAL*"
			(at -0.02032 2.13233 0)
			(unlocked yes)
			(layer "B.Fab")
			(hide yes)
			(effects
				(font
					(size 0.7874 0.5842)
					(thickness 0.1524)
				)
				(justify mirror)
			)
		)
		(property "Tolerance" "TOL*"
			(at -0.044704 3.05435 0)
			(unlocked yes)
			(layer "Cmts.User")
			(hide yes)
			(effects
				(font
					(size 0.7874 0.5842)
					(thickness 0.1524)
				)
				(justify mirror)
			)
		)
		(property "User Part Number" "PARTNUM*"
			(at -0.02032 4.024884 0)
			(unlocked yes)
			(layer "Cmts.User")
			(hide yes)
			(effects
				(font
					(size 0.7874 0.5842)
					(thickness 0.1524)
				)
				(justify mirror)
			)
		)
		(property "Device Type" "RESISTOR-G155-133R0-01,33OHM,1%"
			(at -0.008382 1.210564 0)
			(unlocked yes)
			(layer "B.Fab")
			(hide yes)
			(effects
				(font
					(size 0.7874 0.5842)
					(thickness 0.1524)
				)
				(justify mirror)
			)
		)
		(duplicate_pad_numbers_are_jumpers no)
		(fp_line
			(start -1.143 -0.5588)
			(end 1.143 -0.5588)
			(stroke
				(width 0.1)
				(type default)
			)
			(layer "B.SilkS")
		)
		(fp_line
			(start -1.143 0.5588)
			(end -1.143 -0.5588)
			(stroke
				(width 0.1)
				(type default)
			)
			(layer "B.SilkS")
		)
		(fp_line
			(start 1.143 -0.5588)
			(end 1.143 0.5588)
			(stroke
				(width 0.1)
				(type default)
			)
			(layer "B.SilkS")
		)
		(fp_line
			(start 1.143 0.5588)
			(end -1.143 0.5588)
			(stroke
				(width 0.1)
				(type default)
			)
			(layer "B.SilkS")
		)
		(fp_rect
			(start 1.143 0.5588)
			(end -1.143 -0.5588)
			(stroke
				(width 0)
				(type default)
			)
			(fill no)
			(layer "B.CrtYd")
		)
		(fp_line
			(start -0.508 -0.3048)
			(end 0.508 -0.3048)
			(stroke
				(width 0.1)
				(type default)
			)
			(layer "B.Fab")
		)
		(fp_line
			(start -0.508 0.3048)
			(end -0.508 -0.3048)
			(stroke
				(width 0.1)
				(type default)
			)
			(layer "B.Fab")
		)
		(fp_line
			(start 0.508 -0.3048)
			(end 0.508 0.3048)
			(stroke
				(width 0.1)
				(type default)
			)
			(layer "B.Fab")
		)
		(fp_line
			(start 0.508 0.3048)
			(end -0.508 0.3048)
			(stroke
				(width 0.1)
				(type default)
			)
			(layer "B.Fab")
		)
		(pad "1" smd rect
			(at 0.5334 0 180)
			(size 0.7112 0.6096)
			(layers "B.Cu" "B.Mask" "B.Paste")
			(net "PCIE_SMDAT")
		)
		(pad "2" smd rect
			(at -0.5334 0 180)
			(size 0.7112 0.6096)
			(layers "B.Cu" "B.Mask" "B.Paste")
			(net "R_PCA9546_I2C_SDA")
		)
		(zone
			(layer "B.Cu")
			(hatch none 0.5)
			(connect_pads
				(clearance 0)
			)
			(min_thickness 0.25)
			(keepout
				(tracks allowed)
				(vias not_allowed)
				(pads allowed)
				(copperpour not_allowed)
				(footprints allowed)
			)
			(placement
				(enabled no)
				(sheetname "")
			)
			(fill
				(thermal_gap 0.5)
				(thermal_bridge_width 0.5)
				(island_removal_mode 0)
			)
			(polygon
				(pts
					(xy 21.1328 -40.1828) (xy 21.1328 -40.7924) (xy 20.9804 -40.7924) (xy 20.9804 -40.1828)
				)
			)
		)
	)
	(footprint ""
		(layer "B.Cu")
		(at 105.347008 -37.82314)
		(property "Reference" "C146"
			(at -41.656508 1.37795 0)
			(unlocked yes)
			(layer "B.SilkS")
			(effects
				(font
					(size 0.635 0.4064)
					(thickness 0.1524)
				)
				(justify mirror)
			)
		)
		(property "Value" "VAL*"
			(at 0 3.718306 0)
			(unlocked yes)
			(layer "B.Fab")
			(hide yes)
			(effects
				(font
					(size 0.7874 0.5842)
					(thickness 0.127)
				)
				(justify mirror)
			)
		)
		(property "Tolerance" "TOL*"
			(at 0 4.861306 0)
			(unlocked yes)
			(layer "Cmts.User")
			(hide yes)
			(effects
				(font
					(size 0.7874 0.5842)
					(thickness 0.127)
				)
				(justify mirror)
			)
		)
		(property "User Part Number" "PARTNUM*"
			(at 0 2.575306 0)
			(unlocked yes)
			(layer "Cmts.User")
			(hide yes)
			(effects
				(font
					(size 0.7874 0.5842)
					(thickness 0.127)
				)
				(justify mirror)
			)
		)
		(property "Device Type" "CAPACITOR-G105-0B104-CK,0.1UF,A"
			(at 0 1.432306 0)
			(unlocked yes)
			(layer "B.Fab")
			(hide yes)
			(effects
				(font
					(size 0.7874 0.5842)
					(thickness 0.127)
				)
				(justify mirror)
			)
		)
		(duplicate_pad_numbers_are_jumpers no)
		(fp_line
			(start -0.970026 -0.4699)
			(end -0.970026 0.4699)
			(stroke
				(width 0.1)
				(type default)
			)
			(layer "B.SilkS")
		)
		(fp_line
			(start -0.970026 0.4699)
			(end 0.970026 0.4699)
			(stroke
				(width 0.1)
				(type default)
			)
			(layer "B.SilkS")
		)
		(fp_line
			(start 0.970026 -0.4699)
			(end -0.970026 -0.4699)
			(stroke
				(width 0.1)
				(type default)
			)
			(layer "B.SilkS")
		)
		(fp_line
			(start 0.970026 0.4699)
			(end 0.970026 -0.4699)
			(stroke
				(width 0.1)
				(type default)
			)
			(layer "B.SilkS")
		)
		(fp_poly
			(pts
				(xy 0.970026 0.4699) (xy -0.970026 0.4699) (xy -0.970026 -0.4699) (xy 0.970026 -0.4699)
			)
			(stroke
				(width 0)
				(type default)
			)
			(fill no)
			(layer "B.CrtYd")
		)
		(fp_line
			(start -0.508 -0.3048)
			(end -0.508 0.3048)
			(stroke
				(width 0.1)
				(type default)
			)
			(layer "B.Fab")
		)
		(fp_line
			(start -0.508 0.3048)
			(end 0.508 0.3048)
			(stroke
				(width 0.1)
				(type default)
			)
			(layer "B.Fab")
		)
		(fp_line
			(start 0.508 -0.3048)
			(end -0.508 -0.3048)
			(stroke
				(width 0.1)
				(type default)
			)
			(layer "B.Fab")
		)
		(fp_line
			(start 0.508 0.3048)
			(end 0.508 -0.3048)
			(stroke
				(width 0.1)
				(type default)
			)
			(layer "B.Fab")
		)
		(pad "1" smd circle
			(at 0.500126 0 180)
			(size 0.635 0.635)
			(layers "B.Cu" "B.Mask" "B.Paste")
			(net "XP2R5V_FPGA")
		)
		(pad "2" smd circle
			(at -0.500126 0 180)
			(size 0.635 0.635)
			(layers "B.Cu" "B.Mask" "B.Paste")
			(net "SG")
		)
	)
)
